(kicad_pcb
	(version 20260206)
	(generator "pcbnew")
	(generator_version "10.0")
	(general
		(thickness 1.6)
		(legacy_teardrops no)
	)
	(paper "A4")
	(title_block
		(title "Bryce Canyon_F.DPB_16315-1-OCP.brd")
		(comment 1 "Bryce Canyon / footprints 537-544 of 2223")
	)
	(layers
		(0 "F.Cu" signal "TOP")
		(4 "In1.Cu" signal "L2GND")
		(6 "In2.Cu" signal "L3")
		(8 "In3.Cu" signal "L4GND")
		(10 "In4.Cu" signal "L5")
		(12 "In5.Cu" signal "L6VCC")
		(14 "In6.Cu" signal "L7VCC")
		(16 "In7.Cu" signal "L8")
		(18 "In8.Cu" signal "L9GND")
		(20 "In9.Cu" signal "L10")
		(22 "In10.Cu" signal "L11GND")
		(2 "B.Cu" signal "BOTTOM")
		(9 "F.Adhes" user "F.Adhesive")
		(11 "B.Adhes" user "B.Adhesive")
		(13 "F.Paste" user "Package Geometry/Pastemask Top")
		(15 "B.Paste" user "Package Geometry/Pastemask Bottom")
		(5 "F.SilkS" user "Ref Des/Silkscreen Top")
		(7 "B.SilkS" user "Ref Des/Silkscreen Bottom")
		(1 "F.Mask" user "Board Geometry/Soldermask Top")
		(3 "B.Mask" user "Board Geometry/Soldermask Bottom")
		(17 "Dwgs.User" user "User.Drawings")
		(19 "Cmts.User" user "User.Comments")
		(21 "Eco1.User" user "User.Eco1")
		(23 "Eco2.User" user "User.Eco2")
		(25 "Edge.Cuts" user "Board Geometry/Outline")
		(27 "Margin" user)
		(31 "F.CrtYd" user "Package Geometry/Place Bound Top")
		(29 "B.CrtYd" user "Package Geometry/Place Bound Bottom")
		(35 "F.Fab" user "Ref Des/Assembly Top")
		(33 "B.Fab" user "Ref Des/Assembly Bottom")
	)
	(footprint ""
		(layer "F.Cu")
		(at 466.870796 -277.03653 180)
		(property "Reference" "R400"
			(at 0 0 180)
			(layer "F.SilkS")
			(hide yes)
			(effects
				(font
					(size 1.27 1.27)
				)
			)
		)
		(property "Value" "0R2J-2-GP"
			(at 0.064008 -3.993896 180)
			(unlocked yes)
			(layer "F.Fab")
			(hide yes)
			(effects
				(font
					(size 1.016 1.016)
					(thickness 0.1524)
				)
			)
		)
		(property "Device Type" "R402H16"
			(at 0.064008 -5.517896 180)
			(unlocked yes)
			(layer "F.Fab")
			(hide yes)
			(effects
				(font
					(size 1.016 1.016)
					(thickness 0.1524)
				)
			)
		)
		(duplicate_pad_numbers_are_jumpers no)
		(fp_line
			(start 0.508 -0.9398)
			(end -0.508 -0.9398)
			(stroke
				(width 0.1524)
				(type default)
			)
			(layer "F.SilkS")
		)
		(fp_line
			(start -0.508 -0.9398)
			(end -0.508 0.9398)
			(stroke
				(width 0.1524)
				(type default)
			)
			(layer "F.SilkS")
		)
		(fp_rect
			(start -0.508 0.9398)
			(end 0.508 -0.9398)
			(stroke
				(width 0)
				(type default)
			)
			(fill no)
			(layer "F.CrtYd")
		)
		(fp_rect
			(start -0.508 0.9398)
			(end 0.508 -0.9398)
			(stroke
				(width 0)
				(type default)
			)
			(fill no)
			(layer "F.Fab")
		)
		(pad "1" smd custom
			(at 0 -0.4445 180)
			(size 0.1397 0.1397)
			(layers "F.Cu" "F.Mask" "F.Paste")
			(net "SW_HDD_G11")
			(options
				(clearance outline)
				(anchor circle)
			)
			(primitives
				(gr_poly
					(pts
						(arc
							(start -0.1778 -0.2794)
							(mid -0.249642 -0.249642)
							(end -0.2794 -0.1778)
						)
						(arc
							(start -0.2794 0.1778)
							(mid -0.249642 0.249642)
							(end -0.1778 0.2794)
						)
						(arc
							(start 0.1778 0.2794)
							(mid 0.249642 0.249642)
							(end 0.2794 0.1778)
						)
						(arc
							(start 0.2794 -0.1778)
							(mid 0.249642 -0.249642)
							(end 0.1778 -0.2794)
						)
					)
					(width 0)
					(fill yes)
				)
			)
		)
		(pad "2" smd custom
			(at 0 0.4445 180)
			(size 0.1397 0.1397)
			(layers "F.Cu" "F.Mask" "F.Paste")
			(net "SW_HDD_R11")
			(options
				(clearance outline)
				(anchor circle)
			)
			(primitives
				(gr_poly
					(pts
						(arc
							(start -0.1778 -0.2794)
							(mid -0.249642 -0.249642)
							(end -0.2794 -0.1778)
						)
						(arc
							(start -0.2794 0.1778)
							(mid -0.249642 0.249642)
							(end -0.1778 0.2794)
						)
						(arc
							(start 0.1778 0.2794)
							(mid 0.249642 0.249642)
							(end 0.2794 0.1778)
						)
						(arc
							(start 0.2794 -0.1778)
							(mid 0.249642 -0.249642)
							(end 0.1778 -0.2794)
						)
					)
					(width 0)
					(fill yes)
				)
			)
		)
	)
	(footprint ""
		(layer "F.Cu")
		(at 426.120052 -176.127918 -90)
		(property "Reference" "R612"
			(at 0 0 270)
			(layer "F.SilkS")
			(hide yes)
			(effects
				(font
					(size 1.27 1.27)
				)
			)
		)
		(property "Value" "2R6F-GP"
			(at -0.0508 -4.8514 270)
			(unlocked yes)
			(layer "F.Fab")
			(hide yes)
			(effects
				(font
					(size 1.016 1.016)
					(thickness 0.1524)
				)
			)
		)
		(property "Device Type" "R1206H26"
			(at 0 -6.3754 270)
			(unlocked yes)
			(layer "F.Fab")
			(hide yes)
			(effects
				(font
					(size 1.016 1.016)
					(thickness 0.1524)
				)
			)
		)
		(duplicate_pad_numbers_are_jumpers no)
		(fp_line
			(start -1.016 2.2352)
			(end -1.016 -2.2352)
			(stroke
				(width 0.1524)
				(type default)
			)
			(layer "F.SilkS")
		)
		(fp_line
			(start 1.016 2.2352)
			(end -1.016 2.2352)
			(stroke
				(width 0.1524)
				(type default)
			)
			(layer "F.SilkS")
		)
		(fp_line
			(start -1.016 -2.2352)
			(end 1.016 -2.2352)
			(stroke
				(width 0.1524)
				(type default)
			)
			(layer "F.SilkS")
		)
		(fp_line
			(start 1.016 -2.2352)
			(end 1.016 2.2352)
			(stroke
				(width 0.1524)
				(type default)
			)
			(layer "F.SilkS")
		)
		(fp_rect
			(start -1.0922 2.3114)
			(end 1.0922 -2.3114)
			(stroke
				(width 0)
				(type default)
			)
			(fill no)
			(layer "F.CrtYd")
		)
		(fp_poly
			(pts
				(xy -1.0922 -2.3114) (xy 1.0922 -2.3114) (xy 1.0922 2.3114) (xy -1.0922 2.3114)
			)
			(stroke
				(width 0)
				(type default)
			)
			(fill no)
			(layer "F.Fab")
		)
		(pad "1" smd rect
			(at 0 -1.397 270)
			(size 1.651 1.27)
			(layers "F.Cu" "F.Mask" "F.Paste")
			(net "P5V_HDD21")
		)
		(pad "2" smd rect
			(at 0 1.397 270)
			(size 1.651 1.27)
			(layers "F.Cu" "F.Mask" "F.Paste")
			(net "5V_PRE_21")
		)
	)
	(footprint ""
		(layer "F.Cu")
		(at 224.572322 -129.51587 -90)
		(property "Reference" "TP204"
			(at 0 0 270)
			(layer "F.SilkS")
			(hide yes)
			(effects
				(font
					(size 1.27 1.27)
				)
			)
		)
		(property "Value" "TPAD32-GP"
			(at -0.0508 -1.6764 270)
			(unlocked yes)
			(layer "F.Fab")
			(hide yes)
			(effects
				(font
					(size 1.016 1.016)
					(thickness 0.1524)
				)
			)
		)
		(property "Device Type" "TPAD32"
			(at -0.0508 -3.2004 270)
			(unlocked yes)
			(layer "F.Fab")
			(hide yes)
			(effects
				(font
					(size 1.016 1.016)
					(thickness 0.1524)
				)
			)
		)
		(duplicate_pad_numbers_are_jumpers no)
		(fp_poly
			(pts
				(arc
					(start 0 -0.4064)
					(mid 0 0.4064)
					(end 0 -0.4064)
				)
			)
			(stroke
				(width 0)
				(type default)
			)
			(fill no)
			(layer "F.CrtYd")
		)
		(fp_poly
			(pts
				(arc
					(start 0 -0.7112)
					(mid 0 0.7112)
					(end 0 -0.7112)
				)
			)
			(stroke
				(width 0)
				(type default)
			)
			(fill no)
			(layer "F.Fab")
		)
		(pad "1" smd circle
			(at 0 0 270)
			(size 0.8128 0.8128)
			(layers "F.Cu" "F.Mask" "F.Paste")
			(net "TP_COMP_A_SATA_P0_TX_DN")
		)
	)
	(footprint ""
		(layer "F.Cu")
		(at 447.421 -183.007 -90)
		(property "Reference" "R636"
			(at 0 0 270)
			(layer "F.SilkS")
			(hide yes)
			(effects
				(font
					(size 1.27 1.27)
				)
			)
		)
		(property "Value" "10KR2F-2-GP"
			(at 0.064008 -3.993896 270)
			(unlocked yes)
			(layer "F.Fab")
			(hide yes)
			(effects
				(font
					(size 1.016 1.016)
					(thickness 0.1524)
				)
			)
		)
		(property "Device Type" "R402H16"
			(at 0.064008 -5.517896 270)
			(unlocked yes)
			(layer "F.Fab")
			(hide yes)
			(effects
				(font
					(size 1.016 1.016)
					(thickness 0.1524)
				)
			)
		)
		(duplicate_pad_numbers_are_jumpers no)
		(fp_line
			(start -0.508 -0.9398)
			(end -0.508 0.9398)
			(stroke
				(width 0.1524)
				(type default)
			)
			(layer "F.SilkS")
		)
		(fp_line
			(start 0.508 -0.9398)
			(end -0.508 -0.9398)
			(stroke
				(width 0.1524)
				(type default)
			)
			(layer "F.SilkS")
		)
		(fp_rect
			(start -0.508 0.9398)
			(end 0.508 -0.9398)
			(stroke
				(width 0)
				(type default)
			)
			(fill no)
			(layer "F.CrtYd")
		)
		(fp_rect
			(start -0.508 0.9398)
			(end 0.508 -0.9398)
			(stroke
				(width 0)
				(type default)
			)
			(fill no)
			(layer "F.Fab")
		)
		(pad "1" smd custom
			(at 0 -0.4445 270)
			(size 0.1397 0.1397)
			(layers "F.Cu" "F.Mask" "F.Paste")
			(net "P3V3_STBY_A")
			(options
				(clearance outline)
				(anchor circle)
			)
			(primitives
				(gr_poly
					(pts
						(arc
							(start -0.1778 -0.2794)
							(mid -0.249642 -0.249642)
							(end -0.2794 -0.1778)
						)
						(arc
							(start -0.2794 0.1778)
							(mid -0.249642 0.249642)
							(end -0.1778 0.2794)
						)
						(arc
							(start 0.1778 0.2794)
							(mid 0.249642 0.249642)
							(end 0.2794 0.1778)
						)
						(arc
							(start 0.2794 -0.1778)
							(mid 0.249642 -0.249642)
							(end 0.1778 -0.2794)
						)
					)
					(width 0)
					(fill yes)
				)
			)
		)
		(pad "2" smd custom
			(at 0 0.4445 270)
			(size 0.1397 0.1397)
			(layers "F.Cu" "F.Mask" "F.Paste")
			(net "HDD_PRSNT_22")
			(options
				(clearance outline)
				(anchor circle)
			)
			(primitives
				(gr_poly
					(pts
						(arc
							(start -0.1778 -0.2794)
							(mid -0.249642 -0.249642)
							(end -0.2794 -0.1778)
						)
						(arc
							(start -0.2794 0.1778)
							(mid -0.249642 0.249642)
							(end -0.1778 0.2794)
						)
						(arc
							(start 0.1778 0.2794)
							(mid 0.249642 0.249642)
							(end 0.2794 0.1778)
						)
						(arc
							(start 0.2794 -0.1778)
							(mid 0.249642 -0.249642)
							(end 0.1778 -0.2794)
						)
					)
					(width 0)
					(fill yes)
				)
			)
		)
	)
	(footprint ""
		(layer "F.Cu")
		(at 349.812102 -291.127942 -90)
		(property "Reference" "C136"
			(at 0 0 270)
			(layer "F.SilkS")
			(hide yes)
			(effects
				(font
					(size 1.27 1.27)
				)
			)
		)
		(property "Value" "SCD01U50V2KX-1GP"
			(at 1.1811 -2.7051 270)
			(unlocked yes)
			(layer "F.Fab")
			(hide yes)
			(effects
				(font
					(size 1.016 1.016)
					(thickness 0.1524)
				)
			)
		)
		(property "Device Type" "C402H22"
			(at 1.1811 -4.2291 270)
			(unlocked yes)
			(layer "F.Fab")
			(hide yes)
			(effects
				(font
					(size 1.016 1.016)
					(thickness 0.1524)
				)
			)
		)
		(duplicate_pad_numbers_are_jumpers no)
		(fp_rect
			(start -0.4318 0.9525)
			(end 0.4318 -0.9525)
			(stroke
				(width 0)
				(type default)
			)
			(fill no)
			(layer "F.CrtYd")
		)
		(fp_rect
			(start -0.4318 0.9525)
			(end 0.4318 -0.9525)
			(stroke
				(width 0)
				(type default)
			)
			(fill no)
			(layer "F.Fab")
		)
		(pad "1" smd custom
			(at 0 -0.4445 270)
			(size 0.1524 0.1524)
			(layers "F.Cu" "F.Mask" "F.Paste")
			(net "HDD_PRSNT_7")
			(options
				(clearance outline)
				(anchor circle)
			)
			(primitives
				(gr_poly
					(pts
						(arc
							(start 0.3048 -0.2032)
							(mid 0.275042 -0.275042)
							(end 0.2032 -0.3048)
						)
						(arc
							(start -0.2032 -0.3048)
							(mid -0.275042 -0.275042)
							(end -0.3048 -0.2032)
						)
						(arc
							(start -0.3048 0.2032)
							(mid -0.275042 0.275042)
							(end -0.2032 0.3048)
						)
						(arc
							(start 0.2032 0.3048)
							(mid 0.275042 0.275042)
							(end 0.3048 0.2032)
						)
					)
					(width 0)
					(fill yes)
				)
			)
		)
		(pad "2" smd custom
			(at 0 0.4445 270)
			(size 0.1524 0.1524)
			(layers "F.Cu" "F.Mask" "F.Paste")
			(net "GND")
			(options
				(clearance outline)
				(anchor circle)
			)
			(primitives
				(gr_poly
					(pts
						(arc
							(start 0.3048 -0.2032)
							(mid 0.275042 -0.275042)
							(end 0.2032 -0.3048)
						)
						(arc
							(start -0.2032 -0.3048)
							(mid -0.275042 -0.275042)
							(end -0.3048 -0.2032)
						)
						(arc
							(start -0.3048 0.2032)
							(mid -0.275042 0.275042)
							(end -0.2032 0.3048)
						)
						(arc
							(start 0.2032 0.3048)
							(mid 0.275042 0.275042)
							(end 0.3048 0.2032)
						)
					)
					(width 0)
					(fill yes)
				)
			)
		)
	)
	(footprint ""
		(layer "F.Cu")
		(at 86.924134 -16.94053 -90)
		(property "Reference" "U28"
			(at 0 0 270)
			(layer "F.SilkS")
			(hide yes)
			(effects
				(font
					(size 1.27 1.27)
				)
			)
		)
		(property "Value" "74LVC1G32DC-1GP"
			(at -2.3368 -8.6868 270)
			(unlocked yes)
			(layer "F.Fab")
			(hide yes)
			(effects
				(font
					(size 1.016 1.016)
					(thickness 0.1524)
				)
			)
		)
		(property "Device Type" "SC70-5H44"
			(at -2.3114 -10.414 270)
			(unlocked yes)
			(layer "F.Fab")
			(hide yes)
			(effects
				(font
					(size 1.016 1.016)
					(thickness 0.1524)
				)
			)
		)
		(duplicate_pad_numbers_are_jumpers no)
		(fp_line
			(start -1.27 1.7018)
			(end -1.27 -1.7018)
			(stroke
				(width 0.1524)
				(type default)
			)
			(layer "F.SilkS")
		)
		(fp_line
			(start 1.27 1.7018)
			(end -1.27 1.7018)
			(stroke
				(width 0.1524)
				(type default)
			)
			(layer "F.SilkS")
		)
		(fp_line
			(start -1.27 -1.7018)
			(end 1.27 -1.7018)
			(stroke
				(width 0.1524)
				(type default)
			)
			(layer "F.SilkS")
		)
		(fp_line
			(start 1.27 -1.7018)
			(end 1.27 1.7018)
			(stroke
				(width 0.1524)
				(type default)
			)
			(layer "F.SilkS")
		)
		(fp_line
			(start 0.6604 -1.8034)
			(end 1.3843 -1.8034)
			(stroke
				(width 0.3302)
				(type default)
			)
			(layer "F.SilkS")
		)
		(fp_line
			(start 1.3843 -1.8034)
			(end 1.3843 -1.1176)
			(stroke
				(width 0.3302)
				(type default)
			)
			(layer "F.SilkS")
		)
		(fp_rect
			(start -1.524 1.9558)
			(end 1.524 -1.9558)
			(stroke
				(width 0)
				(type default)
			)
			(fill no)
			(layer "F.CrtYd")
		)
		(fp_poly
			(pts
				(xy -1.524 -1.9558) (xy 1.524 -1.9558) (xy 1.524 1.9558) (xy -1.524 1.9558)
			)
			(stroke
				(width 0)
				(type default)
			)
			(fill no)
			(layer "F.Fab")
		)
		(pad "1" smd rect
			(at 0.65024 -0.8255 270)
			(size 0.4064 1.2192)
			(layers "F.Cu" "F.Mask" "F.Paste")
			(net "COMP_A_PRI_INS_N")
		)
		(pad "2" smd rect
			(at 0 -0.8255 270)
			(size 0.4064 1.2192)
			(layers "F.Cu" "F.Mask" "F.Paste")
			(net "COMP_A_SEC_INS_N")
		)
		(pad "3" smd rect
			(at -0.65024 -0.8255 270)
			(size 0.4064 1.2192)
			(layers "F.Cu" "F.Mask" "F.Paste")
			(net "GND")
		)
		(pad "4" smd rect
			(at -0.65024 0.8255 270)
			(size 0.4064 1.2192)
			(layers "F.Cu" "F.Mask" "F.Paste")
			(net "COMP_A_INS_N")
		)
		(pad "5" smd rect
			(at 0.65024 0.8255 270)
			(size 0.4064 1.2192)
			(layers "F.Cu" "F.Mask" "F.Paste")
			(net "P3V3_STBY_A")
		)
	)
	(footprint ""
		(layer "F.Cu")
		(at 127.399796 -290.061142 90)
		(property "Reference" "C84"
			(at 0 0 90)
			(layer "F.SilkS")
			(hide yes)
			(effects
				(font
					(size 1.27 1.27)
				)
			)
		)
		(property "Value" "SCD01U50V2KX-1GP"
			(at 1.1811 -2.7051 90)
			(unlocked yes)
			(layer "F.Fab")
			(hide yes)
			(effects
				(font
					(size 1.016 1.016)
					(thickness 0.1524)
				)
			)
		)
		(property "Device Type" "C402H22"
			(at 1.1811 -4.2291 90)
			(unlocked yes)
			(layer "F.Fab")
			(hide yes)
			(effects
				(font
					(size 1.016 1.016)
					(thickness 0.1524)
				)
			)
		)
		(duplicate_pad_numbers_are_jumpers no)
		(fp_rect
			(start -0.4318 0.9525)
			(end 0.4318 -0.9525)
			(stroke
				(width 0)
				(type default)
			)
			(fill no)
			(layer "F.CrtYd")
		)
		(fp_rect
			(start -0.4318 0.9525)
			(end 0.4318 -0.9525)
			(stroke
				(width 0)
				(type default)
			)
			(fill no)
			(layer "F.Fab")
		)
		(pad "1" smd custom
			(at 0 -0.4445 90)
			(size 0.1524 0.1524)
			(layers "F.Cu" "F.Mask" "F.Paste")
			(net "HDD_PRSNT_3")
			(options
				(clearance outline)
				(anchor circle)
			)
			(primitives
				(gr_poly
					(pts
						(arc
							(start 0.3048 -0.2032)
							(mid 0.275042 -0.275042)
							(end 0.2032 -0.3048)
						)
						(arc
							(start -0.2032 -0.3048)
							(mid -0.275042 -0.275042)
							(end -0.3048 -0.2032)
						)
						(arc
							(start -0.3048 0.2032)
							(mid -0.275042 0.275042)
							(end -0.2032 0.3048)
						)
						(arc
							(start 0.2032 0.3048)
							(mid 0.275042 0.275042)
							(end 0.3048 0.2032)
						)
					)
					(width 0)
					(fill yes)
				)
			)
		)
		(pad "2" smd custom
			(at 0 0.4445 90)
			(size 0.1524 0.1524)
			(layers "F.Cu" "F.Mask" "F.Paste")
			(net "GND")
			(options
				(clearance outline)
				(anchor circle)
			)
			(primitives
				(gr_poly
					(pts
						(arc
							(start 0.3048 -0.2032)
							(mid 0.275042 -0.275042)
							(end 0.2032 -0.3048)
						)
						(arc
							(start -0.2032 -0.3048)
							(mid -0.275042 -0.275042)
							(end -0.3048 -0.2032)
						)
						(arc
							(start -0.3048 0.2032)
							(mid -0.275042 0.275042)
							(end -0.2032 0.3048)
						)
						(arc
							(start 0.2032 0.3048)
							(mid 0.275042 0.275042)
							(end 0.3048 0.2032)
						)
					)
					(width 0)
					(fill yes)
				)
			)
		)
	)
	(footprint ""
		(layer "F.Cu")
		(at 426.755052 -160.252918 -90)
		(property "Reference" "Q127"
			(at 0 0 270)
			(layer "F.SilkS")
			(hide yes)
			(effects
				(font
					(size 1.27 1.27)
				)
			)
		)
		(property "Value" "2N7002KDW-GP"
			(at -2.3622 -8.2042 270)
			(unlocked yes)
			(layer "F.Fab")
			(hide yes)
			(effects
				(font
					(size 1.016 1.016)
					(thickness 0.1524)
				)
			)
		)
		(property "Device Type" "SOT-363H44"
			(at -2.3622 -10.1092 270)
			(unlocked yes)
			(layer "F.Fab")
			(hide yes)
			(effects
				(font
					(size 1.016 1.016)
					(thickness 0.1524)
				)
			)
		)
		(duplicate_pad_numbers_are_jumpers no)
		(fp_line
			(start -1.4478 1.7018)
			(end 1.4478 1.7018)
			(stroke
				(width 0.1524)
				(type default)
			)
			(layer "F.SilkS")
		)
		(fp_line
			(start 1.4478 1.7018)
			(end 1.4478 -1.7018)
			(stroke
				(width 0.1524)
				(type default)
			)
			(layer "F.SilkS")
		)
		(fp_line
			(start -1.27 1.524)
			(end -1.27 0.6604)
			(stroke
				(width 0.4826)
				(type default)
			)
			(layer "F.SilkS")
		)
		(fp_line
			(start -1.4478 -1.7018)
			(end -1.4478 1.7018)
			(stroke
				(width 0.1524)
				(type default)
			)
			(layer "F.SilkS")
		)
		(fp_line
			(start 1.4478 -1.7018)
			(end -1.4478 -1.7018)
			(stroke
				(width 0.1524)
				(type default)
			)
			(layer "F.SilkS")
		)
		(fp_poly
			(pts
				(xy -1.524 -1.778) (xy 1.524 -1.778) (xy 1.524 1.778) (xy -1.524 1.778)
			)
			(stroke
				(width 0)
				(type default)
			)
			(fill no)
			(layer "F.CrtYd")
		)
		(fp_poly
			(pts
				(xy -1.524 -1.778) (xy 1.524 -1.778) (xy 1.524 1.778) (xy -1.524 1.778)
			)
			(stroke
				(width 0)
				(type default)
			)
			(fill no)
			(layer "F.Fab")
		)
		(pad "1" smd rect
			(at -0.65024 0.9398 270)
			(size 0.4064 1.016)
			(layers "F.Cu" "F.Mask" "F.Paste")
			(net "GND")
		)
		(pad "2" smd rect
			(at 0 0.9398 270)
			(size 0.4064 1.016)
			(layers "F.Cu" "F.Mask" "F.Paste")
			(net "SW_PWR_R_HDD21")
		)
		(pad "3" smd rect
			(at 0.65024 0.9398 270)
			(size 0.4064 1.016)
			(layers "F.Cu" "F.Mask" "F.Paste")
			(net "SW_HDD_P21")
		)
		(pad "4" smd rect
			(at 0.65024 -0.9398 270)
			(size 0.4064 1.016)
			(layers "F.Cu" "F.Mask" "F.Paste")
			(net "GND")
		)
		(pad "5" smd rect
			(at 0 -0.9398 270)
			(size 0.4064 1.016)
			(layers "F.Cu" "F.Mask" "F.Paste")
			(net "SW_HDD_G21")
		)
		(pad "6" smd rect
			(at -0.65024 -0.9398 270)
			(size 0.4064 1.016)
			(layers "F.Cu" "F.Mask" "F.Paste")
			(net "SW_HDD_R21")
		)
	)
)
